(kicad_pcb
	(version 20260206)
	(generator "pcbnew")
	(generator_version "10.0")
	(general
		(thickness 1.6)
		(legacy_teardrops no)
	)
	(paper "A4")
	(title_block
		(title "03242023_DA0F0TMBIJ0_F0T_Motherboard_J_brd_V01_OCP.brd")
		(comment 1 "Grand Teton / footprint 2188 of 6105 (J19), pads 225-291 of 291")
	)
	(layers
		(0 "F.Cu" signal "TOP")
		(4 "In1.Cu" signal "GND")
		(6 "In2.Cu" signal "IN1")
		(8 "In3.Cu" signal "GND1")
		(10 "In4.Cu" signal "IN2")
		(12 "In5.Cu" signal "GND2")
		(14 "In6.Cu" signal "IN3")
		(16 "In7.Cu" signal "GND3")
		(18 "In8.Cu" signal "VCC")
		(20 "In9.Cu" signal "VCC1")
		(22 "In10.Cu" signal "GND4")
		(24 "In11.Cu" signal "IN4")
		(26 "In12.Cu" signal "GND5")
		(28 "In13.Cu" signal "IN5")
		(30 "In14.Cu" signal "GND6")
		(32 "In15.Cu" signal "IN6")
		(34 "In16.Cu" signal "GND7")
		(2 "B.Cu" signal "BOTTOM")
		(9 "F.Adhes" user "F.Adhesive")
		(11 "B.Adhes" user "B.Adhesive")
		(13 "F.Paste" user "Package Geometry/Pastemask Top")
		(15 "B.Paste" user "Package Geometry/Pastemask Bottom")
		(5 "F.SilkS" user "Ref Des/Silkscreen Top")
		(7 "B.SilkS" user "Ref Des/Silkscreen Bottom")
		(1 "F.Mask" user "Board Geometry/Soldermask Top")
		(3 "B.Mask" user "Board Geometry/Soldermask Bottom")
		(17 "Dwgs.User" user "User.Drawings")
		(19 "Cmts.User" user "User.Comments")
		(21 "Eco1.User" user "User.Eco1")
		(23 "Eco2.User" user "User.Eco2")
		(25 "Edge.Cuts" user "Board Geometry/Outline")
		(27 "Margin" user)
		(31 "F.CrtYd" user "Package Geometry/Place Bound Top")
		(29 "B.CrtYd" user "Package Geometry/Place Bound Bottom")
		(35 "F.Fab" user "Ref Des/Assembly Top")
		(33 "B.Fab" user "Ref Des/Assembly Bottom")
	)
	(footprint ""
		(layer "F.Cu")
		(at 40.36568 -258.091686)
		(property "Reference" "J19"
			(at -5.21716 -81.970372 0)
			(unlocked yes)
			(layer "F.SilkS")
			(effects
				(font
					(size 0.7874 0.5842)
					(thickness 0.1524)
				)
				(justify left)
			)
		)
		(property "Value" ""
			(at 0 0 0)
			(layer "F.Fab")
			(effects
				(font
					(size 1.27 1.27)
				)
			)
		)
		(duplicate_pad_numbers_are_jumpers no)
		(pad "225" smd rect
			(at 2.050034 9.774936 270)
			(size 0.519938 1.4986)
			(layers "F.Cu" "F.Mask" "F.Paste")
			(net "M_B_CPU1_SB_CA<5>")
		)
		(pad "226" smd rect
			(at 2.050034 10.625074 270)
			(size 0.519938 1.4986)
			(layers "F.Cu" "F.Mask" "F.Paste")
			(net "GND")
		)
		(pad "227" smd rect
			(at 2.050034 11.474958 270)
			(size 0.519938 1.4986)
			(layers "F.Cu" "F.Mask" "F.Paste")
			(net "M_B_CPU1_SB_PAR")
		)
		(pad "228" smd rect
			(at 2.050034 12.325096 270)
			(size 0.519938 1.4986)
			(layers "F.Cu" "F.Mask" "F.Paste")
			(net "GND")
		)
		(pad "229" smd rect
			(at 2.050034 13.17498 270)
			(size 0.519938 1.4986)
			(layers "F.Cu" "F.Mask" "F.Paste")
			(net "M_B_CPU1_SB_CS_N<1>")
		)
		(pad "230" smd rect
			(at 2.050034 14.025118 270)
			(size 0.519938 1.4986)
			(layers "F.Cu" "F.Mask" "F.Paste")
			(net "GND")
		)
		(pad "231" smd rect
			(at 2.050034 14.875002 270)
			(size 0.519938 1.4986)
			(layers "F.Cu" "F.Mask" "F.Paste")
			(net "TP_CHB_CPU1_DIMM1_FRU_5")
		)
		(pad "232" smd rect
			(at 2.050034 15.724886 270)
			(size 0.519938 1.4986)
			(layers "F.Cu" "F.Mask" "F.Paste")
			(net "TP_CHB_CPU1_DIMM1_FRU_6")
		)
		(pad "233" smd rect
			(at 2.050034 16.575024 270)
			(size 0.519938 1.4986)
			(layers "F.Cu" "F.Mask" "F.Paste")
			(net "GND")
		)
		(pad "234" smd rect
			(at 2.050034 17.424908 270)
			(size 0.519938 1.4986)
			(layers "F.Cu" "F.Mask" "F.Paste")
			(net "M_B_CPU1_SB_CB<6>")
		)
		(pad "235" smd rect
			(at 2.050034 18.275046 270)
			(size 0.519938 1.4986)
			(layers "F.Cu" "F.Mask" "F.Paste")
			(net "GND")
		)
		(pad "236" smd rect
			(at 2.050034 19.12493 270)
			(size 0.519938 1.4986)
			(layers "F.Cu" "F.Mask" "F.Paste")
			(net "M_B_CPU1_SB_CB<7>")
		)
		(pad "237" smd rect
			(at 2.050034 19.975068 270)
			(size 0.519938 1.4986)
			(layers "F.Cu" "F.Mask" "F.Paste")
			(net "GND")
		)
		(pad "238" smd rect
			(at 2.050034 20.824952 270)
			(size 0.519938 1.4986)
			(layers "F.Cu" "F.Mask" "F.Paste")
			(net "M_B_CPU1_SB_DQS_DN<4>")
		)
		(pad "239" smd rect
			(at 2.050034 21.67509 270)
			(size 0.519938 1.4986)
			(layers "F.Cu" "F.Mask" "F.Paste")
			(net "M_B_CPU1_SB_DQS_DP<4>")
		)
		(pad "240" smd rect
			(at 2.050034 22.524974 270)
			(size 0.519938 1.4986)
			(layers "F.Cu" "F.Mask" "F.Paste")
			(net "GND")
		)
		(pad "241" smd rect
			(at 2.050034 23.375112 270)
			(size 0.519938 1.4986)
			(layers "F.Cu" "F.Mask" "F.Paste")
			(net "M_B_CPU1_SB_CB<2>")
		)
		(pad "242" smd rect
			(at 2.050034 24.224996 270)
			(size 0.519938 1.4986)
			(layers "F.Cu" "F.Mask" "F.Paste")
			(net "GND")
		)
		(pad "243" smd rect
			(at 2.050034 25.07488 270)
			(size 0.519938 1.4986)
			(layers "F.Cu" "F.Mask" "F.Paste")
			(net "M_B_CPU1_SB_CB<3>")
		)
		(pad "244" smd rect
			(at 2.050034 25.925018 270)
			(size 0.519938 1.4986)
			(layers "F.Cu" "F.Mask" "F.Paste")
			(net "GND")
		)
		(pad "245" smd rect
			(at 2.050034 26.774902 270)
			(size 0.519938 1.4986)
			(layers "F.Cu" "F.Mask" "F.Paste")
			(net "M_B_CPU1_SB_DQ<2>")
		)
		(pad "246" smd rect
			(at 2.050034 27.62504 270)
			(size 0.519938 1.4986)
			(layers "F.Cu" "F.Mask" "F.Paste")
			(net "GND")
		)
		(pad "247" smd rect
			(at 2.050034 28.474924 270)
			(size 0.519938 1.4986)
			(layers "F.Cu" "F.Mask" "F.Paste")
			(net "M_B_CPU1_SB_DQ<3>")
		)
		(pad "248" smd rect
			(at 2.050034 29.325062 270)
			(size 0.519938 1.4986)
			(layers "F.Cu" "F.Mask" "F.Paste")
			(net "GND")
		)
		(pad "249" smd rect
			(at 2.050034 30.174946 270)
			(size 0.519938 1.4986)
			(layers "F.Cu" "F.Mask" "F.Paste")
			(net "M_B_CPU1_SB_DQS_DN<5>")
		)
		(pad "250" smd rect
			(at 2.050034 31.025084 270)
			(size 0.519938 1.4986)
			(layers "F.Cu" "F.Mask" "F.Paste")
			(net "M_B_CPU1_SB_DQS_DP<5>")
		)
		(pad "251" smd rect
			(at 2.050034 31.874968 270)
			(size 0.519938 1.4986)
			(layers "F.Cu" "F.Mask" "F.Paste")
			(net "GND")
		)
		(pad "252" smd rect
			(at 2.050034 32.725106 270)
			(size 0.519938 1.4986)
			(layers "F.Cu" "F.Mask" "F.Paste")
			(net "M_B_CPU1_SB_DQ<6>")
		)
		(pad "253" smd rect
			(at 2.050034 33.57499 270)
			(size 0.519938 1.4986)
			(layers "F.Cu" "F.Mask" "F.Paste")
			(net "GND")
		)
		(pad "254" smd rect
			(at 2.050034 34.425128 270)
			(size 0.519938 1.4986)
			(layers "F.Cu" "F.Mask" "F.Paste")
			(net "M_B_CPU1_SB_DQ<7>")
		)
		(pad "255" smd rect
			(at 2.050034 35.275012 270)
			(size 0.519938 1.4986)
			(layers "F.Cu" "F.Mask" "F.Paste")
			(net "GND")
		)
		(pad "256" smd rect
			(at 2.050034 36.124896 270)
			(size 0.519938 1.4986)
			(layers "F.Cu" "F.Mask" "F.Paste")
			(net "M_B_CPU1_SB_DQ<10>")
		)
		(pad "257" smd rect
			(at 2.050034 36.975034 270)
			(size 0.519938 1.4986)
			(layers "F.Cu" "F.Mask" "F.Paste")
			(net "GND")
		)
		(pad "258" smd rect
			(at 2.050034 37.824918 270)
			(size 0.519938 1.4986)
			(layers "F.Cu" "F.Mask" "F.Paste")
			(net "M_B_CPU1_SB_DQ<11>")
		)
		(pad "259" smd rect
			(at 2.050034 38.675056 270)
			(size 0.519938 1.4986)
			(layers "F.Cu" "F.Mask" "F.Paste")
			(net "GND")
		)
		(pad "260" smd rect
			(at 2.050034 39.52494 270)
			(size 0.519938 1.4986)
			(layers "F.Cu" "F.Mask" "F.Paste")
			(net "M_B_CPU1_SB_DQS_DN<6>")
		)
		(pad "261" smd rect
			(at 2.050034 40.375078 270)
			(size 0.519938 1.4986)
			(layers "F.Cu" "F.Mask" "F.Paste")
			(net "M_B_CPU1_SB_DQS_DP<6>")
		)
		(pad "262" smd rect
			(at 2.050034 41.224962 270)
			(size 0.519938 1.4986)
			(layers "F.Cu" "F.Mask" "F.Paste")
			(net "GND")
		)
		(pad "263" smd rect
			(at 2.050034 42.0751 270)
			(size 0.519938 1.4986)
			(layers "F.Cu" "F.Mask" "F.Paste")
			(net "M_B_CPU1_SB_DQ<14>")
		)
		(pad "264" smd rect
			(at 2.050034 42.924984 270)
			(size 0.519938 1.4986)
			(layers "F.Cu" "F.Mask" "F.Paste")
			(net "GND")
		)
		(pad "265" smd rect
			(at 2.050034 43.775122 270)
			(size 0.519938 1.4986)
			(layers "F.Cu" "F.Mask" "F.Paste")
			(net "M_B_CPU1_SB_DQ<15>")
		)
		(pad "266" smd rect
			(at 2.050034 44.625006 270)
			(size 0.519938 1.4986)
			(layers "F.Cu" "F.Mask" "F.Paste")
			(net "GND")
		)
		(pad "267" smd rect
			(at 2.050034 45.47489 270)
			(size 0.519938 1.4986)
			(layers "F.Cu" "F.Mask" "F.Paste")
			(net "M_B_CPU1_SB_DQ<18>")
		)
		(pad "268" smd rect
			(at 2.050034 46.325028 270)
			(size 0.519938 1.4986)
			(layers "F.Cu" "F.Mask" "F.Paste")
			(net "GND")
		)
		(pad "269" smd rect
			(at 2.050034 47.174912 270)
			(size 0.519938 1.4986)
			(layers "F.Cu" "F.Mask" "F.Paste")
			(net "M_B_CPU1_SB_DQ<19>")
		)
		(pad "270" smd rect
			(at 2.050034 48.02505 270)
			(size 0.519938 1.4986)
			(layers "F.Cu" "F.Mask" "F.Paste")
			(net "GND")
		)
		(pad "271" smd rect
			(at 2.050034 48.874934 270)
			(size 0.519938 1.4986)
			(layers "F.Cu" "F.Mask" "F.Paste")
			(net "M_B_CPU1_SB_DQS_DN<7>")
		)
		(pad "272" smd rect
			(at 2.050034 49.725072 270)
			(size 0.519938 1.4986)
			(layers "F.Cu" "F.Mask" "F.Paste")
			(net "M_B_CPU1_SB_DQS_DP<7>")
		)
		(pad "273" smd rect
			(at 2.050034 50.574956 270)
			(size 0.519938 1.4986)
			(layers "F.Cu" "F.Mask" "F.Paste")
			(net "GND")
		)
		(pad "274" smd rect
			(at 2.050034 51.425094 270)
			(size 0.519938 1.4986)
			(layers "F.Cu" "F.Mask" "F.Paste")
			(net "M_B_CPU1_SB_DQ<22>")
		)
		(pad "275" smd rect
			(at 2.050034 52.274978 270)
			(size 0.519938 1.4986)
			(layers "F.Cu" "F.Mask" "F.Paste")
			(net "GND")
		)
		(pad "276" smd rect
			(at 2.050034 53.125116 270)
			(size 0.519938 1.4986)
			(layers "F.Cu" "F.Mask" "F.Paste")
			(net "M_B_CPU1_SB_DQ<23>")
		)
		(pad "277" smd rect
			(at 2.050034 53.975 270)
			(size 0.519938 1.4986)
			(layers "F.Cu" "F.Mask" "F.Paste")
			(net "GND")
		)
		(pad "278" smd rect
			(at 2.050034 54.824884 270)
			(size 0.519938 1.4986)
			(layers "F.Cu" "F.Mask" "F.Paste")
			(net "M_B_CPU1_SB_DQ<26>")
		)
		(pad "279" smd rect
			(at 2.050034 55.675022 270)
			(size 0.519938 1.4986)
			(layers "F.Cu" "F.Mask" "F.Paste")
			(net "GND")
		)
		(pad "280" smd rect
			(at 2.050034 56.524906 270)
			(size 0.519938 1.4986)
			(layers "F.Cu" "F.Mask" "F.Paste")
			(net "M_B_CPU1_SB_DQ<27>")
		)
		(pad "281" smd rect
			(at 2.050034 57.375044 270)
			(size 0.519938 1.4986)
			(layers "F.Cu" "F.Mask" "F.Paste")
			(net "GND")
		)
		(pad "282" smd rect
			(at 2.050034 58.224928 270)
			(size 0.519938 1.4986)
			(layers "F.Cu" "F.Mask" "F.Paste")
			(net "M_B_CPU1_SB_DQS_DN<8>")
		)
		(pad "283" smd rect
			(at 2.050034 59.075066 270)
			(size 0.519938 1.4986)
			(layers "F.Cu" "F.Mask" "F.Paste")
			(net "M_B_CPU1_SB_DQS_DP<8>")
		)
		(pad "284" smd rect
			(at 2.050034 59.92495 270)
			(size 0.519938 1.4986)
			(layers "F.Cu" "F.Mask" "F.Paste")
			(net "GND")
		)
		(pad "285" smd rect
			(at 2.050034 60.775088 270)
			(size 0.519938 1.4986)
			(layers "F.Cu" "F.Mask" "F.Paste")
			(net "M_B_CPU1_SB_DQ<30>")
		)
		(pad "286" smd rect
			(at 2.050034 61.624972 270)
			(size 0.519938 1.4986)
			(layers "F.Cu" "F.Mask" "F.Paste")
			(net "GND")
		)
		(pad "287" smd rect
			(at 2.050034 62.47511 270)
			(size 0.519938 1.4986)
			(layers "F.Cu" "F.Mask" "F.Paste")
			(net "M_B_CPU1_SB_DQ<31>")
		)
		(pad "288" smd rect
			(at 2.050034 63.324994 270)
			(size 0.519938 1.4986)
			(layers "F.Cu" "F.Mask" "F.Paste")
			(net "GND")
		)
		(pad "G1" thru_hole oval
			(at 0 -68.97497)
			(size 2.8194 1.5748)
			(drill oval 2.4384 1.1938)
			(layers "*.Cu" "*.Mask")
			(remove_unused_layers no)
			(net "GND")
			(clearance 0.127)
			(thermal_gap 0.127)
		)
		(pad "G2" thru_hole oval
			(at 0 3.875024)
			(size 2.8194 1.5748)
			(drill oval 2.4384 1.1938)
			(layers "*.Cu" "*.Mask")
			(remove_unused_layers no)
			(net "GND")
			(clearance 0.127)
			(thermal_gap 0.127)
		)
		(pad "G3" thru_hole oval
			(at 0 68.97497)
			(size 2.8194 1.5748)
			(drill oval 2.4384 1.1938)
			(layers "*.Cu" "*.Mask")
			(remove_unused_layers no)
			(net "GND")
			(clearance 0.127)
			(thermal_gap 0.127)
		)
	)
)
